(kicad_pcb
	(version 20241229)
	(generator "pcbnew")
	(generator_version "9.0")
	(general
		(thickness 1.294)
		(legacy_teardrops no)
	)
	(paper "A3")
	(title_block
		(title "Kintex 410T devboard")
		(date "2024-04-03")
		(rev "1.1.2")
		(comment 9 "footprint 170 of 975 (U1), pads 787-850 of 900")
	)
	(layers
		(0 "F.Cu" mixed)
		(4 "In1.Cu" power)
		(6 "In2.Cu" power)
		(8 "In3.Cu" mixed)
		(10 "In4.Cu" power)
		(12 "In5.Cu" mixed)
		(14 "In6.Cu" power)
		(16 "In7.Cu" mixed)
		(18 "In8.Cu" power)
		(2 "B.Cu" mixed)
		(9 "F.Adhes" user "F.Adhesive")
		(11 "B.Adhes" user "B.Adhesive")
		(13 "F.Paste" user)
		(15 "B.Paste" user)
		(5 "F.SilkS" user "F.Silkscreen")
		(7 "B.SilkS" user "B.Silkscreen")
		(1 "F.Mask" user)
		(3 "B.Mask" user)
		(17 "Dwgs.User" user "User.Drawings")
		(19 "Cmts.User" user "User.Comments")
		(21 "Eco1.User" user "User.Eco1")
		(23 "Eco2.User" user "User.Eco2")
		(25 "Edge.Cuts" user)
		(27 "Margin" user)
		(31 "F.CrtYd" user "F.Courtyard")
		(29 "B.CrtYd" user "B.Courtyard")
		(35 "F.Fab" user)
		(33 "B.Fab" user)
	)
	(footprint "antmicro-footprints:BGA-900_31x31mm_Layout30x30_P1x1mm_FFG900"
		(locked yes)
		(layer "F.Cu")
		(at 200 130)
		(property "Reference" "U1"
			(at -15.74 -15.78 0)
			(layer "F.SilkS")
			(effects
				(font
					(size 0.7 0.7)
					(thickness 0.15)
				)
				(justify left bottom)
			)
		)
		(property "Value" "XC7K410T-2FFG900I"
			(at -4.436 17.635 0)
			(layer "F.Fab")
			(effects
				(font
					(size 0.7 0.7)
					(thickness 0.15)
				)
				(justify left bottom)
			)
		)
		(property "Description" "FPGA, Kintex-7, MMCM, PLL, 350 I/O's, 710 MHz, 406720 Cells, 970 mV to 1.03 V, FCBGA-900"
			(at 0 0 0)
			(layer "F.Fab")
			(hide yes)
			(effects
				(font
					(size 1.27 1.27)
					(thickness 0.15)
				)
			)
		)
		(property "Author" "Antmicro"
			(at 0 0 0)
			(layer "F.Fab")
			(hide yes)
			(effects
				(font
					(size 1 1)
					(thickness 0.15)
				)
			)
		)
		(property "License" "Apache-2.0"
			(at 0 0 0)
			(layer "F.Fab")
			(hide yes)
			(effects
				(font
					(size 1 1)
					(thickness 0.15)
				)
			)
		)
		(property "MPN" "XC7K410T-2FFG900I"
			(at 0 0 0)
			(layer "F.Fab")
			(hide yes)
			(effects
				(font
					(size 1 1)
					(thickness 0.15)
				)
			)
		)
		(property "Manufacturer" "AMD-Xilinx"
			(at 0 0 0)
			(layer "F.Fab")
			(hide yes)
			(effects
				(font
					(size 1 1)
					(thickness 0.15)
				)
			)
		)
		(sheetname "FPGA supply")
		(sheetfile "fpga-supply.kicad_sch")
		(attr smd)
		(pad "U7" smd circle
			(at -8.5 1.5)
			(size 0.5 0.5)
			(property pad_prop_bga)
			(layers "F.Cu" "F.Mask" "F.Paste")
			(net 592 "/FMC+ HSPC/GTX115.REFCLK1_N")
			(pinfunction "MGTREFCLK1N_115")
			(pintype "bidirectional")
			(die_length 8.79)
			(solder_mask_margin 0.02)
		)
		(pad "U8" smd circle
			(at -7.5 1.5)
			(size 0.5 0.5)
			(property pad_prop_bga)
			(layers "F.Cu" "F.Mask" "F.Paste")
			(net 591 "/FMC+ HSPC/GTX115.REFCLK1_P")
			(pinfunction "MGTREFCLK1P_115")
			(pintype "bidirectional")
			(die_length 8.447)
			(solder_mask_margin 0.02)
		)
		(pad "U9" smd circle
			(at -6.5 1.5)
			(size 0.5 0.5)
			(property pad_prop_bga)
			(layers "F.Cu" "F.Mask" "F.Paste")
			(net 1 "GND")
			(pinfunction "GND")
			(pintype "passive")
			(solder_mask_margin 0.02)
		)
		(pad "U10" smd circle
			(at -5.5 1.5)
			(size 0.5 0.5)
			(property pad_prop_bga)
			(layers "F.Cu" "F.Mask" "F.Paste")
			(net 650 "+1V0")
			(pinfunction "VCCINT")
			(pintype "passive")
			(solder_mask_margin 0.02)
		)
		(pad "U11" smd circle
			(at -4.5 1.5)
			(size 0.5 0.5)
			(property pad_prop_bga)
			(layers "F.Cu" "F.Mask" "F.Paste")
			(net 1 "GND")
			(pinfunction "GND")
			(pintype "passive")
			(solder_mask_margin 0.02)
		)
		(pad "U12" smd circle
			(at -3.5 1.5)
			(size 0.5 0.5)
			(property pad_prop_bga)
			(layers "F.Cu" "F.Mask" "F.Paste")
			(net 650 "+1V0")
			(pinfunction "VCCINT")
			(pintype "passive")
			(solder_mask_margin 0.02)
		)
		(pad "U13" smd circle
			(at -2.5 1.5)
			(size 0.5 0.5)
			(property pad_prop_bga)
			(layers "F.Cu" "F.Mask" "F.Paste")
			(net 1 "GND")
			(pinfunction "GND")
			(pintype "passive")
			(solder_mask_margin 0.02)
		)
		(pad "U14" smd circle
			(at -1.5 1.5)
			(size 0.5 0.5)
			(property pad_prop_bga)
			(layers "F.Cu" "F.Mask" "F.Paste")
			(net 9 "/FPGA Config/FPGA_CFG_DXN")
			(pinfunction "DXN_0")
			(pintype "bidirectional")
			(die_length 11.927)
			(solder_mask_margin 0.02)
		)
		(pad "U15" smd circle
			(at -0.5 1.5)
			(size 0.5 0.5)
			(property pad_prop_bga)
			(layers "F.Cu" "F.Mask" "F.Paste")
			(net 10 "/FPGA Config/FPGA_CFG_DXP")
			(pinfunction "DXP_0")
			(pintype "bidirectional")
			(die_length 10.856)
			(solder_mask_margin 0.02)
		)
		(pad "U16" smd circle
			(at 0.5 1.5)
			(size 0.5 0.5)
			(property pad_prop_bga)
			(layers "F.Cu" "F.Mask" "F.Paste")
			(net 650 "+1V0")
			(pinfunction "VCCBRAM")
			(pintype "passive")
			(solder_mask_margin 0.02)
		)
		(pad "U17" smd circle
			(at 1.5 1.5)
			(size 0.5 0.5)
			(property pad_prop_bga)
			(layers "F.Cu" "F.Mask" "F.Paste")
			(net 1 "GND")
			(pinfunction "GND")
			(pintype "passive")
			(solder_mask_margin 0.02)
		)
		(pad "U18" smd circle
			(at 2.5 1.5)
			(size 0.5 0.5)
			(property pad_prop_bga)
			(layers "F.Cu" "F.Mask" "F.Paste")
			(net 650 "+1V0")
			(pinfunction "VCCINT")
			(pintype "passive")
			(solder_mask_margin 0.02)
		)
		(pad "U19" smd circle
			(at 3.5 1.5)
			(size 0.5 0.5)
			(property pad_prop_bga)
			(layers "F.Cu" "F.Mask" "F.Paste")
			(net 75 "/FPGA Bank 14 & 15/SYSTEM_FLASH.~{CS}")
			(pinfunction "IO_L6P_T0_FCS_B_14")
			(pintype "bidirectional")
			(die_length 8.184)
			(solder_mask_margin 0.02)
		)
		(pad "U20" smd circle
			(at 4.5 1.5)
			(size 0.5 0.5)
			(property pad_prop_bga)
			(layers "F.Cu" "F.Mask" "F.Paste")
			(net 676 "/DRAM + SRAM/SRAM.DQ4")
			(pinfunction "IO_L6N_T0_D08_VREF_14")
			(pintype "bidirectional")
			(die_length 6.954)
			(solder_mask_margin 0.02)
		)
		(pad "U21" smd circle
			(at 5.5 1.5)
			(size 0.5 0.5)
			(property pad_prop_bga)
			(layers "F.Cu" "F.Mask" "F.Paste")
			(net 24 "+3V3")
			(pinfunction "VCCO_14")
			(pintype "passive")
			(solder_mask_margin 0.02)
		)
		(pad "U22" smd circle
			(at 6.5 1.5)
			(size 0.5 0.5)
			(property pad_prop_bga)
			(layers "F.Cu" "F.Mask" "F.Paste")
			(net 562 "/DRAM + SRAM/SRAM.CE2")
			(pinfunction "IO_L21P_T3_DQS_14")
			(pintype "bidirectional")
			(die_length 11.116)
			(solder_mask_margin 0.02)
		)
		(pad "U23" smd circle
			(at 7.5 1.5)
			(size 0.5 0.5)
			(property pad_prop_bga)
			(layers "F.Cu" "F.Mask" "F.Paste")
			(net 677 "/DRAM + SRAM/SRAM.A14")
			(pinfunction "IO_L21N_T3_DQS_A06_D22_14")
			(pintype "bidirectional")
			(die_length 11.023)
			(solder_mask_margin 0.02)
		)
		(pad "U24" smd circle
			(at 8.5 1.5)
			(size 0.5 0.5)
			(property pad_prop_bga)
			(layers "F.Cu" "F.Mask" "F.Paste")
			(net 1045 "unconnected-(U1B-IO_L23P_T3_A03_D19_14-PadU24)")
			(pinfunction "IO_L23P_T3_A03_D19_14")
			(pintype "bidirectional+no_connect")
			(die_length 10.857)
			(solder_mask_margin 0.02)
		)
		(pad "U25" smd circle
			(at 9.5 1.5)
			(size 0.5 0.5)
			(property pad_prop_bga)
			(layers "F.Cu" "F.Mask" "F.Paste")
			(net 678 "/DRAM + SRAM/SRAM.A11")
			(pinfunction "IO_L14N_T2_SRCC_14")
			(pintype "bidirectional")
			(die_length 11.788)
			(solder_mask_margin 0.02)
		)
		(pad "U26" smd circle
			(at 10.5 1.5)
			(size 0.5 0.5)
			(property pad_prop_bga)
			(layers "F.Cu" "F.Mask" "F.Paste")
			(net 1 "GND")
			(pinfunction "GND")
			(pintype "passive")
			(solder_mask_margin 0.02)
		)
		(pad "U27" smd circle
			(at 11.5 1.5)
			(size 0.5 0.5)
			(property pad_prop_bga)
			(layers "F.Cu" "F.Mask" "F.Paste")
			(net 679 "/DRAM + SRAM/SRAM.A10")
			(pinfunction "IO_L13P_T2_MRCC_14")
			(pintype "bidirectional")
			(die_length 13.108)
			(solder_mask_margin 0.02)
		)
		(pad "U28" smd circle
			(at 12.5 1.5)
			(size 0.5 0.5)
			(property pad_prop_bga)
			(layers "F.Cu" "F.Mask" "F.Paste")
			(net 680 "/DRAM + SRAM/SRAM.A0")
			(pinfunction "IO_L13N_T2_MRCC_14")
			(pintype "bidirectional")
			(die_length 13.478)
			(solder_mask_margin 0.02)
		)
		(pad "U29" smd circle
			(at 13.5 1.5)
			(size 0.5 0.5)
			(property pad_prop_bga)
			(layers "F.Cu" "F.Mask" "F.Paste")
			(net 1384 "/SUP_MCU.SPARE2")
			(pinfunction "IO_L15P_T2_DQS_RDWR_B_14")
			(pintype "bidirectional")
			(die_length 14.917)
			(solder_mask_margin 0.02)
		)
		(pad "U30" smd circle
			(at 14.5 1.5)
			(size 0.5 0.5)
			(property pad_prop_bga)
			(layers "F.Cu" "F.Mask" "F.Paste")
			(net 1046 "unconnected-(U1B-IO_L15N_T2_DQS_DOUT_CSO_B_14-PadU30)")
			(pinfunction "IO_L15N_T2_DQS_DOUT_CSO_B_14")
			(pintype "bidirectional+no_connect")
			(die_length 15.496)
			(solder_mask_margin 0.02)
		)
		(pad "V1" smd circle
			(at -14.5 2.5)
			(size 0.5 0.5)
			(property pad_prop_bga)
			(layers "F.Cu" "F.Mask" "F.Paste")
			(net 115 "/FMC+ HSPC/GTX115.TX1_N")
			(pinfunction "MGTXTXN1_115")
			(pintype "bidirectional")
			(die_length 14.451)
			(solder_mask_margin 0.02)
		)
		(pad "V2" smd circle
			(at -13.5 2.5)
			(size 0.5 0.5)
			(property pad_prop_bga)
			(layers "F.Cu" "F.Mask" "F.Paste")
			(net 107 "/FMC+ HSPC/GTX115.TX1_P")
			(pinfunction "MGTXTXP1_115")
			(pintype "bidirectional")
			(die_length 14.516)
			(solder_mask_margin 0.02)
		)
		(pad "V3" smd circle
			(at -12.5 2.5)
			(size 0.5 0.5)
			(property pad_prop_bga)
			(layers "F.Cu" "F.Mask" "F.Paste")
			(net 8 "+1V2_MGTAVTT")
			(pinfunction "MGTAVTT")
			(pintype "passive")
			(solder_mask_margin 0.02)
		)
		(pad "V4" smd circle
			(at -11.5 2.5)
			(size 0.5 0.5)
			(property pad_prop_bga)
			(layers "F.Cu" "F.Mask" "F.Paste")
			(net 1 "GND")
			(pinfunction "GND")
			(pintype "passive")
			(solder_mask_margin 0.02)
		)
		(pad "V5" smd circle
			(at -10.5 2.5)
			(size 0.5 0.5)
			(property pad_prop_bga)
			(layers "F.Cu" "F.Mask" "F.Paste")
			(net 473 "/FMC+ HSPC/GTX115.RX3_N")
			(pinfunction "MGTXRXN3_115")
			(pintype "bidirectional")
			(die_length 13.463)
			(solder_mask_margin 0.02)
		)
		(pad "V6" smd circle
			(at -9.5 2.5)
			(size 0.5 0.5)
			(property pad_prop_bga)
			(layers "F.Cu" "F.Mask" "F.Paste")
			(net 479 "/FMC+ HSPC/GTX115.RX3_P")
			(pinfunction "MGTXRXP3_115")
			(pintype "bidirectional")
			(die_length 13.634)
			(solder_mask_margin 0.02)
		)
		(pad "V7" smd circle
			(at -8.5 2.5)
			(size 0.5 0.5)
			(property pad_prop_bga)
			(layers "F.Cu" "F.Mask" "F.Paste")
			(net 26 "+1V8")
			(pinfunction "MGTVCCAUX")
			(pintype "passive")
			(solder_mask_margin 0.02)
		)
		(pad "V8" smd circle
			(at -7.5 2.5)
			(size 0.5 0.5)
			(property pad_prop_bga)
			(layers "F.Cu" "F.Mask" "F.Paste")
			(net 1 "GND")
			(pinfunction "GND")
			(pintype "passive")
			(solder_mask_margin 0.02)
		)
		(pad "V9" smd circle
			(at -6.5 2.5)
			(size 0.5 0.5)
			(property pad_prop_bga)
			(layers "F.Cu" "F.Mask" "F.Paste")
			(net 1 "GND")
			(pinfunction "GND")
			(pintype "passive")
			(solder_mask_margin 0.02)
		)
		(pad "V10" smd circle
			(at -5.5 2.5)
			(size 0.5 0.5)
			(property pad_prop_bga)
			(layers "F.Cu" "F.Mask" "F.Paste")
			(net 1 "GND")
			(pinfunction "GND")
			(pintype "passive")
			(solder_mask_margin 0.02)
		)
		(pad "V11" smd circle
			(at -4.5 2.5)
			(size 0.5 0.5)
			(property pad_prop_bga)
			(layers "F.Cu" "F.Mask" "F.Paste")
			(net 26 "+1V8")
			(pinfunction "VCCAUX_IO_G0")
			(pintype "bidirectional")
			(solder_mask_margin 0.02)
		)
		(pad "V12" smd circle
			(at -3.5 2.5)
			(size 0.5 0.5)
			(property pad_prop_bga)
			(layers "F.Cu" "F.Mask" "F.Paste")
			(net 1 "GND")
			(pinfunction "GND")
			(pintype "passive")
			(solder_mask_margin 0.02)
		)
		(pad "V13" smd circle
			(at -2.5 2.5)
			(size 0.5 0.5)
			(property pad_prop_bga)
			(layers "F.Cu" "F.Mask" "F.Paste")
			(net 26 "+1V8")
			(pinfunction "VCCAUX")
			(pintype "passive")
			(solder_mask_margin 0.02)
		)
		(pad "V14" smd circle
			(at -1.5 2.5)
			(size 0.5 0.5)
			(property pad_prop_bga)
			(layers "F.Cu" "F.Mask" "F.Paste")
			(net 1 "GND")
			(pinfunction "GND")
			(pintype "passive")
			(solder_mask_margin 0.02)
		)
		(pad "V15" smd circle
			(at -0.5 2.5)
			(size 0.5 0.5)
			(property pad_prop_bga)
			(layers "F.Cu" "F.Mask" "F.Paste")
			(net 26 "+1V8")
			(pinfunction "VCCAUX")
			(pintype "passive")
			(solder_mask_margin 0.02)
		)
		(pad "V16" smd circle
			(at 0.5 2.5)
			(size 0.5 0.5)
			(property pad_prop_bga)
			(layers "F.Cu" "F.Mask" "F.Paste")
			(net 1 "GND")
			(pinfunction "GND")
			(pintype "passive")
			(solder_mask_margin 0.02)
		)
		(pad "V17" smd circle
			(at 1.5 2.5)
			(size 0.5 0.5)
			(property pad_prop_bga)
			(layers "F.Cu" "F.Mask" "F.Paste")
			(net 650 "+1V0")
			(pinfunction "VCCINT")
			(pintype "passive")
			(solder_mask_margin 0.02)
		)
		(pad "V18" smd circle
			(at 2.5 2.5)
			(size 0.5 0.5)
			(property pad_prop_bga)
			(layers "F.Cu" "F.Mask" "F.Paste")
			(net 1 "GND")
			(pinfunction "GND")
			(pintype "passive")
			(solder_mask_margin 0.02)
		)
		(pad "V19" smd circle
			(at 3.5 2.5)
			(size 0.5 0.5)
			(property pad_prop_bga)
			(layers "F.Cu" "F.Mask" "F.Paste")
			(net 681 "/DRAM + SRAM/SRAM.A12")
			(pinfunction "IO_L19P_T3_A10_D26_14")
			(pintype "bidirectional")
			(die_length 8.087)
			(solder_mask_margin 0.02)
		)
		(pad "V20" smd circle
			(at 4.5 2.5)
			(size 0.5 0.5)
			(property pad_prop_bga)
			(layers "F.Cu" "F.Mask" "F.Paste")
			(net 682 "/DRAM + SRAM/SRAM.A4")
			(pinfunction "IO_L19N_T3_A09_D25_VREF_14")
			(pintype "bidirectional")
			(die_length 8.502)
			(solder_mask_margin 0.02)
		)
		(pad "V21" smd circle
			(at 5.5 2.5)
			(size 0.5 0.5)
			(property pad_prop_bga)
			(layers "F.Cu" "F.Mask" "F.Paste")
			(net 683 "/DRAM + SRAM/SRAM.DQ0")
			(pinfunction "IO_L22P_T3_A05_D21_14")
			(pintype "bidirectional")
			(die_length 8.935)
			(solder_mask_margin 0.02)
		)
		(pad "V22" smd circle
			(at 6.5 2.5)
			(size 0.5 0.5)
			(property pad_prop_bga)
			(layers "F.Cu" "F.Mask" "F.Paste")
			(net 1048 "unconnected-(U1B-IO_L22N_T3_A04_D20_14-PadV22)")
			(pinfunction "IO_L22N_T3_A04_D20_14")
			(pintype "bidirectional+no_connect")
			(die_length 8.194)
			(solder_mask_margin 0.02)
		)
		(pad "V23" smd circle
			(at 7.5 2.5)
			(size 0.5 0.5)
			(property pad_prop_bga)
			(layers "F.Cu" "F.Mask" "F.Paste")
			(net 1 "GND")
			(pinfunction "GND")
			(pintype "passive")
			(solder_mask_margin 0.02)
		)
		(pad "V24" smd circle
			(at 8.5 2.5)
			(size 0.5 0.5)
			(property pad_prop_bga)
			(layers "F.Cu" "F.Mask" "F.Paste")
			(net 684 "/DRAM + SRAM/SRAM.A7")
			(pinfunction "IO_L23N_T3_A02_D18_14")
			(pintype "bidirectional")
			(die_length 9.102)
			(solder_mask_margin 0.02)
		)
		(pad "V25" smd circle
			(at 9.5 2.5)
			(size 0.5 0.5)
			(property pad_prop_bga)
			(layers "F.Cu" "F.Mask" "F.Paste")
			(net 685 "/DRAM + SRAM/SRAM.A18")
			(pinfunction "IO_L18P_T2_A12_D28_14")
			(pintype "bidirectional")
			(die_length 11.952)
			(solder_mask_margin 0.02)
		)
		(pad "V26" smd circle
			(at 10.5 2.5)
			(size 0.5 0.5)
			(property pad_prop_bga)
			(layers "F.Cu" "F.Mask" "F.Paste")
			(net 1383 "/SUP_MCU.SPARE1")
			(pinfunction "IO_L16P_T2_CSI_B_14")
			(pintype "bidirectional")
			(die_length 12.076)
			(solder_mask_margin 0.02)
		)
		(pad "V27" smd circle
			(at 11.5 2.5)
			(size 0.5 0.5)
			(property pad_prop_bga)
			(layers "F.Cu" "F.Mask" "F.Paste")
			(net 556 "/DRAM + SRAM/SRAM.~{CE}")
			(pinfunction "IO_L16N_T2_A15_D31_14")
			(pintype "bidirectional")
			(die_length 12.112)
			(solder_mask_margin 0.02)
		)
		(pad "V28" smd circle
			(at 12.5 2.5)
			(size 0.5 0.5)
			(property pad_prop_bga)
			(layers "F.Cu" "F.Mask" "F.Paste")
			(net 24 "+3V3")
			(pinfunction "VCCO_14")
			(pintype "passive")
			(solder_mask_margin 0.02)
		)
		(pad "V29" smd circle
			(at 13.5 2.5)
			(size 0.5 0.5)
			(property pad_prop_bga)
			(layers "F.Cu" "F.Mask" "F.Paste")
			(net 686 "/DRAM + SRAM/SRAM.A1")
			(pinfunction "IO_L17P_T2_A14_D30_14")
			(pintype "bidirectional")
			(die_length 14.653)
			(solder_mask_margin 0.02)
		)
		(pad "V30" smd circle
			(at 14.5 2.5)
			(size 0.5 0.5)
			(property pad_prop_bga)
			(layers "F.Cu" "F.Mask" "F.Paste")
			(net 687 "/DRAM + SRAM/SRAM.DQ1")
			(pinfunction "IO_L17N_T2_A13_D29_14")
			(pintype "bidirectional")
			(die_length 15.213)
			(solder_mask_margin 0.02)
		)
		(pad "W1" smd circle
			(at -14.5 3.5)
			(size 0.5 0.5)
			(property pad_prop_bga)
			(layers "F.Cu" "F.Mask" "F.Paste")
			(net 1 "GND")
			(pinfunction "GND")
			(pintype "passive")
			(solder_mask_margin 0.02)
		)
		(pad "W2" smd circle
			(at -13.5 3.5)
			(size 0.5 0.5)
			(property pad_prop_bga)
			(layers "F.Cu" "F.Mask" "F.Paste")
			(net 1 "GND")
			(pinfunction "GND")
			(pintype "passive")
			(solder_mask_margin 0.02)
		)
		(pad "W3" smd circle
			(at -12.5 3.5)
			(size 0.5 0.5)
			(property pad_prop_bga)
			(layers "F.Cu" "F.Mask" "F.Paste")
			(net 454 "/FMC+ HSPC/GTX115.RX2_N")
			(pinfunction "MGTXRXN2_115")
			(pintype "bidirectional")
			(die_length 15.13)
			(solder_mask_margin 0.02)
		)
		(pad "W4" smd circle
			(at -11.5 3.5)
			(size 0.5 0.5)
			(property pad_prop_bga)
			(layers "F.Cu" "F.Mask" "F.Paste")
			(net 459 "/FMC+ HSPC/GTX115.RX2_P")
			(pinfunction "MGTXRXP2_115")
			(pintype "bidirectional")
			(die_length 15.15)
			(solder_mask_margin 0.02)
		)
		(pad "W5" smd circle
			(at -10.5 3.5)
			(size 0.5 0.5)
			(property pad_prop_bga)
			(layers "F.Cu" "F.Mask" "F.Paste")
			(net 8 "+1V2_MGTAVTT")
			(pinfunction "MGTAVTT")
			(pintype "passive")
			(solder_mask_margin 0.02)
		)
		(pad "W6" smd circle
			(at -9.5 3.5)
			(size 0.5 0.5)
			(property pad_prop_bga)
			(layers "F.Cu" "F.Mask" "F.Paste")
			(net 1 "GND")
			(pinfunction "GND")
			(pintype "passive")
			(solder_mask_margin 0.02)
		)
		(pad "W7" smd circle
			(at -8.5 3.5)
			(size 0.5 0.5)
			(property pad_prop_bga)
			(layers "F.Cu" "F.Mask" "F.Paste")
			(net 8 "+1V2_MGTAVTT")
			(pinfunction "MGTAVTTRCAL_115")
			(pintype "bidirectional")
			(die_length 10.818)
			(solder_mask_margin 0.02)
		)
		(pad "W8" smd circle
			(at -7.5 3.5)
			(size 0.5 0.5)
			(property pad_prop_bga)
			(layers "F.Cu" "F.Mask" "F.Paste")
			(net 494 "/FPGA supply/MGTRREF")
			(pinfunction "MGTRREF_115")
			(pintype "bidirectional")
			(die_length 9.623)
			(solder_mask_margin 0.02)
		)
		(pad "W9" smd circle
			(at -6.5 3.5)
			(size 0.5 0.5)
			(property pad_prop_bga)
			(layers "F.Cu" "F.Mask" "F.Paste")
			(net 1 "GND")
			(pinfunction "GND")
			(pintype "passive")
			(solder_mask_margin 0.02)
		)
		(pad "W10" smd circle
			(at -5.5 3.5)
			(size 0.5 0.5)
			(property pad_prop_bga)
			(layers "F.Cu" "F.Mask" "F.Paste")
			(net 26 "+1V8")
			(pinfunction "VCCAUX_IO_G0")
			(pintype "passive")
			(solder_mask_margin 0.02)
		)
	)
)
